(kicad_pcb
	(version 20260206)
	(generator "pcbnew")
	(generator_version "10.0")
	(general
		(thickness 1.6)
		(legacy_teardrops no)
	)
	(paper "A4")
	(title_block
		(title "03242023_DA0F0TMBIJ0_F0T_Motherboard_J_brd_V01_OCP.brd")
		(comment 1 "Grand Teton / footprints 1580-1584 of 6105")
	)
	(layers
		(0 "F.Cu" signal "TOP")
		(4 "In1.Cu" signal "GND")
		(6 "In2.Cu" signal "IN1")
		(8 "In3.Cu" signal "GND1")
		(10 "In4.Cu" signal "IN2")
		(12 "In5.Cu" signal "GND2")
		(14 "In6.Cu" signal "IN3")
		(16 "In7.Cu" signal "GND3")
		(18 "In8.Cu" signal "VCC")
		(20 "In9.Cu" signal "VCC1")
		(22 "In10.Cu" signal "GND4")
		(24 "In11.Cu" signal "IN4")
		(26 "In12.Cu" signal "GND5")
		(28 "In13.Cu" signal "IN5")
		(30 "In14.Cu" signal "GND6")
		(32 "In15.Cu" signal "IN6")
		(34 "In16.Cu" signal "GND7")
		(2 "B.Cu" signal "BOTTOM")
		(9 "F.Adhes" user "F.Adhesive")
		(11 "B.Adhes" user "B.Adhesive")
		(13 "F.Paste" user "Package Geometry/Pastemask Top")
		(15 "B.Paste" user "Package Geometry/Pastemask Bottom")
		(5 "F.SilkS" user "Ref Des/Silkscreen Top")
		(7 "B.SilkS" user "Ref Des/Silkscreen Bottom")
		(1 "F.Mask" user "Board Geometry/Soldermask Top")
		(3 "B.Mask" user "Board Geometry/Soldermask Bottom")
		(17 "Dwgs.User" user "User.Drawings")
		(19 "Cmts.User" user "User.Comments")
		(21 "Eco1.User" user "User.Eco1")
		(23 "Eco2.User" user "User.Eco2")
		(25 "Edge.Cuts" user "Board Geometry/Outline")
		(27 "Margin" user)
		(31 "F.CrtYd" user "Package Geometry/Place Bound Top")
		(29 "B.CrtYd" user "Package Geometry/Place Bound Bottom")
		(35 "F.Fab" user "Ref Des/Assembly Top")
		(33 "B.Fab" user "Ref Des/Assembly Bottom")
	)
	(footprint ""
		(layer "F.Cu")
		(at 354.687632 -397.519398 180)
		(property "Reference" "R2674"
			(at 0 0 180)
			(layer "F.SilkS")
			(hide yes)
			(effects
				(font
					(size 1.27 1.27)
				)
			)
		)
		(property "Value" ""
			(at 0 0 180)
			(layer "F.Fab")
			(effects
				(font
					(size 1.27 1.27)
				)
			)
		)
		(duplicate_pad_numbers_are_jumpers no)
		(fp_line
			(start 0.7874 0.4064)
			(end -0.7874 0.4064)
			(stroke
				(width 0.1524)
				(type default)
			)
			(layer "F.SilkS")
		)
		(fp_line
			(start 0.7874 -0.4064)
			(end 0.7874 0.4064)
			(stroke
				(width 0.1524)
				(type default)
			)
			(layer "F.SilkS")
		)
		(fp_line
			(start -0.7874 0.4064)
			(end -0.7874 -0.4064)
			(stroke
				(width 0.1524)
				(type default)
			)
			(layer "F.SilkS")
		)
		(fp_line
			(start -0.7874 -0.4064)
			(end 0.7874 -0.4064)
			(stroke
				(width 0.1524)
				(type default)
			)
			(layer "F.SilkS")
		)
		(fp_line
			(start 0.67945 0.3048)
			(end 0.120396 0.3048)
			(stroke
				(width 0.1)
				(type default)
			)
			(layer "F.Fab")
		)
		(fp_line
			(start 0.67945 -0.3048)
			(end 0.67945 0.3048)
			(stroke
				(width 0.1)
				(type default)
			)
			(layer "F.Fab")
		)
		(fp_line
			(start 0.12065 -0.2794)
			(end 0.12065 -0.3048)
			(stroke
				(width 0.1)
				(type default)
			)
			(layer "F.Fab")
		)
		(fp_line
			(start 0.12065 -0.3048)
			(end 0.67945 -0.3048)
			(stroke
				(width 0.1)
				(type default)
			)
			(layer "F.Fab")
		)
		(fp_line
			(start 0.120396 0.3048)
			(end 0.120396 0.2794)
			(stroke
				(width 0.1)
				(type default)
			)
			(layer "F.Fab")
		)
		(fp_line
			(start 0.120396 0.2794)
			(end -0.12065 0.2794)
			(stroke
				(width 0.1)
				(type default)
			)
			(layer "F.Fab")
		)
		(fp_line
			(start -0.12065 0.3048)
			(end -0.67945 0.3048)
			(stroke
				(width 0.1)
				(type default)
			)
			(layer "F.Fab")
		)
		(fp_line
			(start -0.12065 0.2794)
			(end -0.12065 0.3048)
			(stroke
				(width 0.1)
				(type default)
			)
			(layer "F.Fab")
		)
		(fp_line
			(start -0.12065 -0.2794)
			(end 0.12065 -0.2794)
			(stroke
				(width 0.1)
				(type default)
			)
			(layer "F.Fab")
		)
		(fp_line
			(start -0.12065 -0.305054)
			(end -0.12065 -0.2794)
			(stroke
				(width 0.1)
				(type default)
			)
			(layer "F.Fab")
		)
		(fp_line
			(start -0.67945 0.3048)
			(end -0.67945 -0.305054)
			(stroke
				(width 0.1)
				(type default)
			)
			(layer "F.Fab")
		)
		(fp_line
			(start -0.67945 -0.305054)
			(end -0.12065 -0.305054)
			(stroke
				(width 0.1)
				(type default)
			)
			(layer "F.Fab")
		)
		(pad "1" smd circle
			(at -0.40005 0 180)
			(size 0 0)
			(layers "F.Cu" "F.Mask" "F.Paste")
			(net "I3C_BMC_SWB_BUF_R_SDA")
		)
		(pad "2" smd circle
			(at 0.40005 0 180)
			(size 0 0)
			(layers "F.Cu" "F.Mask" "F.Paste")
			(net "I3C_BMC_SWB_BUF_SDA")
		)
	)
	(footprint ""
		(layer "F.Cu")
		(at 459.267814 -380.572772)
		(property "Reference" "PR92"
			(at 0 0 0)
			(layer "F.SilkS")
			(hide yes)
			(effects
				(font
					(size 1.27 1.27)
				)
			)
		)
		(property "Value" ""
			(at 0 0 0)
			(layer "F.Fab")
			(effects
				(font
					(size 1.27 1.27)
				)
			)
		)
		(duplicate_pad_numbers_are_jumpers no)
		(fp_line
			(start -0.7874 -0.4064)
			(end 0.7874 -0.4064)
			(stroke
				(width 0.1524)
				(type default)
			)
			(layer "F.SilkS")
		)
		(fp_line
			(start -0.7874 0.4064)
			(end -0.7874 -0.4064)
			(stroke
				(width 0.1524)
				(type default)
			)
			(layer "F.SilkS")
		)
		(fp_line
			(start 0.7874 -0.4064)
			(end 0.7874 0.4064)
			(stroke
				(width 0.1524)
				(type default)
			)
			(layer "F.SilkS")
		)
		(fp_line
			(start 0.7874 0.4064)
			(end -0.7874 0.4064)
			(stroke
				(width 0.1524)
				(type default)
			)
			(layer "F.SilkS")
		)
		(fp_line
			(start -0.67945 -0.305054)
			(end -0.12065 -0.305054)
			(stroke
				(width 0.1)
				(type default)
			)
			(layer "F.Fab")
		)
		(fp_line
			(start -0.67945 0.3048)
			(end -0.67945 -0.305054)
			(stroke
				(width 0.1)
				(type default)
			)
			(layer "F.Fab")
		)
		(fp_line
			(start -0.12065 -0.305054)
			(end -0.12065 -0.2794)
			(stroke
				(width 0.1)
				(type default)
			)
			(layer "F.Fab")
		)
		(fp_line
			(start -0.12065 -0.2794)
			(end 0.12065 -0.2794)
			(stroke
				(width 0.1)
				(type default)
			)
			(layer "F.Fab")
		)
		(fp_line
			(start -0.12065 0.2794)
			(end -0.12065 0.3048)
			(stroke
				(width 0.1)
				(type default)
			)
			(layer "F.Fab")
		)
		(fp_line
			(start -0.12065 0.3048)
			(end -0.67945 0.3048)
			(stroke
				(width 0.1)
				(type default)
			)
			(layer "F.Fab")
		)
		(fp_line
			(start 0.120396 0.2794)
			(end -0.12065 0.2794)
			(stroke
				(width 0.1)
				(type default)
			)
			(layer "F.Fab")
		)
		(fp_line
			(start 0.120396 0.3048)
			(end 0.120396 0.2794)
			(stroke
				(width 0.1)
				(type default)
			)
			(layer "F.Fab")
		)
		(fp_line
			(start 0.12065 -0.3048)
			(end 0.67945 -0.3048)
			(stroke
				(width 0.1)
				(type default)
			)
			(layer "F.Fab")
		)
		(fp_line
			(start 0.12065 -0.2794)
			(end 0.12065 -0.3048)
			(stroke
				(width 0.1)
				(type default)
			)
			(layer "F.Fab")
		)
		(fp_line
			(start 0.67945 -0.3048)
			(end 0.67945 0.3048)
			(stroke
				(width 0.1)
				(type default)
			)
			(layer "F.Fab")
		)
		(fp_line
			(start 0.67945 0.3048)
			(end 0.120396 0.3048)
			(stroke
				(width 0.1)
				(type default)
			)
			(layer "F.Fab")
		)
		(pad "1" smd circle
			(at -0.40005 0)
			(size 0 0)
			(layers "F.Cu" "F.Mask" "F.Paste")
			(net "P5V_AUX_FB")
		)
		(pad "2" smd circle
			(at 0.40005 0)
			(size 0 0)
			(layers "F.Cu" "F.Mask" "F.Paste")
			(net "P5V_AUX")
		)
	)
	(footprint ""
		(layer "F.Cu")
		(at 420.4716 -160.452562 180)
		(property "Reference" "PC636"
			(at 0 0 180)
			(layer "F.SilkS")
			(hide yes)
			(effects
				(font
					(size 1.27 1.27)
				)
			)
		)
		(property "Value" ""
			(at 0 0 180)
			(layer "F.Fab")
			(effects
				(font
					(size 1.27 1.27)
				)
			)
		)
		(duplicate_pad_numbers_are_jumpers no)
		(fp_line
			(start 0.7874 0.4064)
			(end -0.7874 0.4064)
			(stroke
				(width 0.1524)
				(type default)
			)
			(layer "F.SilkS")
		)
		(fp_line
			(start 0.7874 -0.4064)
			(end 0.7874 0.4064)
			(stroke
				(width 0.1524)
				(type default)
			)
			(layer "F.SilkS")
		)
		(fp_line
			(start -0.7874 0.4064)
			(end -0.7874 -0.4064)
			(stroke
				(width 0.1524)
				(type default)
			)
			(layer "F.SilkS")
		)
		(fp_line
			(start -0.7874 -0.4064)
			(end 0.7874 -0.4064)
			(stroke
				(width 0.1524)
				(type default)
			)
			(layer "F.SilkS")
		)
		(fp_line
			(start 0.67945 0.3048)
			(end 0.120396 0.3048)
			(stroke
				(width 0.1)
				(type default)
			)
			(layer "F.Fab")
		)
		(fp_line
			(start 0.67945 -0.3048)
			(end 0.67945 0.3048)
			(stroke
				(width 0.1)
				(type default)
			)
			(layer "F.Fab")
		)
		(fp_line
			(start 0.12065 -0.2794)
			(end 0.12065 -0.3048)
			(stroke
				(width 0.1)
				(type default)
			)
			(layer "F.Fab")
		)
		(fp_line
			(start 0.12065 -0.3048)
			(end 0.67945 -0.3048)
			(stroke
				(width 0.1)
				(type default)
			)
			(layer "F.Fab")
		)
		(fp_line
			(start 0.120396 0.3048)
			(end 0.120396 0.2794)
			(stroke
				(width 0.1)
				(type default)
			)
			(layer "F.Fab")
		)
		(fp_line
			(start 0.120396 0.2794)
			(end -0.12065 0.2794)
			(stroke
				(width 0.1)
				(type default)
			)
			(layer "F.Fab")
		)
		(fp_line
			(start -0.12065 0.3048)
			(end -0.67945 0.3048)
			(stroke
				(width 0.1)
				(type default)
			)
			(layer "F.Fab")
		)
		(fp_line
			(start -0.12065 0.2794)
			(end -0.12065 0.3048)
			(stroke
				(width 0.1)
				(type default)
			)
			(layer "F.Fab")
		)
		(fp_line
			(start -0.12065 -0.2794)
			(end 0.12065 -0.2794)
			(stroke
				(width 0.1)
				(type default)
			)
			(layer "F.Fab")
		)
		(fp_line
			(start -0.12065 -0.305054)
			(end -0.12065 -0.2794)
			(stroke
				(width 0.1)
				(type default)
			)
			(layer "F.Fab")
		)
		(fp_line
			(start -0.67945 0.3048)
			(end -0.67945 -0.305054)
			(stroke
				(width 0.1)
				(type default)
			)
			(layer "F.Fab")
		)
		(fp_line
			(start -0.67945 -0.305054)
			(end -0.12065 -0.305054)
			(stroke
				(width 0.1)
				(type default)
			)
			(layer "F.Fab")
		)
		(pad "1" smd circle
			(at -0.40005 0 180)
			(size 0 0)
			(layers "F.Cu" "F.Mask" "F.Paste")
			(net "SW_PVCCD_HV_CPU0_BOOT1_R")
		)
		(pad "2" smd circle
			(at 0.40005 0 180)
			(size 0 0)
			(layers "F.Cu" "F.Mask" "F.Paste")
			(net "SW_PVCCD_HV_CPU0_BOOTR1")
		)
	)
	(footprint ""
		(layer "F.Cu")
		(at 219.347034 -75.02779 -90)
		(property "Reference" "PC2208"
			(at 0 0 270)
			(layer "F.SilkS")
			(hide yes)
			(effects
				(font
					(size 1.27 1.27)
				)
			)
		)
		(property "Value" ""
			(at 0 0 270)
			(layer "F.Fab")
			(effects
				(font
					(size 1.27 1.27)
				)
			)
		)
		(duplicate_pad_numbers_are_jumpers no)
		(fp_line
			(start -0.7874 0.4064)
			(end -0.7874 -0.4064)
			(stroke
				(width 0.1524)
				(type default)
			)
			(layer "F.SilkS")
		)
		(fp_line
			(start 0.7874 0.4064)
			(end -0.7874 0.4064)
			(stroke
				(width 0.1524)
				(type default)
			)
			(layer "F.SilkS")
		)
		(fp_line
			(start -0.7874 -0.4064)
			(end 0.7874 -0.4064)
			(stroke
				(width 0.1524)
				(type default)
			)
			(layer "F.SilkS")
		)
		(fp_line
			(start 0.7874 -0.4064)
			(end 0.7874 0.4064)
			(stroke
				(width 0.1524)
				(type default)
			)
			(layer "F.SilkS")
		)
		(fp_line
			(start -0.67945 0.3048)
			(end -0.67945 -0.305054)
			(stroke
				(width 0.1)
				(type default)
			)
			(layer "F.Fab")
		)
		(fp_line
			(start -0.12065 0.3048)
			(end -0.67945 0.3048)
			(stroke
				(width 0.1)
				(type default)
			)
			(layer "F.Fab")
		)
		(fp_line
			(start 0.120396 0.3048)
			(end 0.120396 0.2794)
			(stroke
				(width 0.1)
				(type default)
			)
			(layer "F.Fab")
		)
		(fp_line
			(start 0.67945 0.3048)
			(end 0.120396 0.3048)
			(stroke
				(width 0.1)
				(type default)
			)
			(layer "F.Fab")
		)
		(fp_line
			(start -0.12065 0.2794)
			(end -0.12065 0.3048)
			(stroke
				(width 0.1)
				(type default)
			)
			(layer "F.Fab")
		)
		(fp_line
			(start 0.120396 0.2794)
			(end -0.12065 0.2794)
			(stroke
				(width 0.1)
				(type default)
			)
			(layer "F.Fab")
		)
		(fp_line
			(start -0.12065 -0.2794)
			(end 0.12065 -0.2794)
			(stroke
				(width 0.1)
				(type default)
			)
			(layer "F.Fab")
		)
		(fp_line
			(start 0.12065 -0.2794)
			(end 0.12065 -0.3048)
			(stroke
				(width 0.1)
				(type default)
			)
			(layer "F.Fab")
		)
		(fp_line
			(start 0.12065 -0.3048)
			(end 0.67945 -0.3048)
			(stroke
				(width 0.1)
				(type default)
			)
			(layer "F.Fab")
		)
		(fp_line
			(start 0.67945 -0.3048)
			(end 0.67945 0.3048)
			(stroke
				(width 0.1)
				(type default)
			)
			(layer "F.Fab")
		)
		(fp_line
			(start -0.67945 -0.305054)
			(end -0.12065 -0.305054)
			(stroke
				(width 0.1)
				(type default)
			)
			(layer "F.Fab")
		)
		(fp_line
			(start -0.12065 -0.305054)
			(end -0.12065 -0.2794)
			(stroke
				(width 0.1)
				(type default)
			)
			(layer "F.Fab")
		)
		(pad "1" smd circle
			(at -0.40005 0 270)
			(size 0 0)
			(layers "F.Cu" "F.Mask" "F.Paste")
			(net "P3V3_AUX")
		)
		(pad "2" smd circle
			(at 0.40005 0 270)
			(size 0 0)
			(layers "F.Cu" "F.Mask" "F.Paste")
			(net "GND")
		)
	)
	(footprint ""
		(layer "F.Cu")
		(at 35.171126 -136.386062 -90)
		(property "Reference" "PJ50"
			(at -0.650494 -1.97866 0)
			(unlocked yes)
			(layer "F.SilkS")
			(effects
				(font
					(size 0.7874 0.5842)
					(thickness 0.1524)
				)
				(justify left)
			)
		)
		(property "Value" ""
			(at 0 0 270)
			(layer "F.Fab")
			(effects
				(font
					(size 1.27 1.27)
				)
			)
		)
		(duplicate_pad_numbers_are_jumpers no)
		(pad "1" smd circle
			(at -0.7493 0)
			(size 0 0)
			(layers "F.Cu" "F.Mask" "F.Paste")
			(net "VSENSE_PVCCINFAON_CPU1_DP")
		)
		(pad "2" smd rect
			(at 0.7493 0 180)
			(size 0.7112 0.8128)
			(layers "F.Cu" "F.Mask" "F.Paste")
			(net "SH_PVCCINFAON_CPU1")
		)
		(zone
			(layer "F.Cu")
			(hatch none 0.5)
			(connect_pads
				(clearance 0)
			)
			(min_thickness 0.25)
			(keepout
				(tracks allowed)
				(vias not_allowed)
				(pads allowed)
				(copperpour not_allowed)
				(footprints allowed)
			)
			(placement
				(enabled no)
				(sheetname "")
			)
			(fill
				(thermal_gap 0.5)
				(thermal_bridge_width 0.5)
				(island_removal_mode 0)
			)
			(polygon
				(pts
					(xy 34.7599 -135.179562) (xy 35.577526 -135.179562) (xy 35.577526 -137.567162) (xy 34.7599 -137.567162)
				)
			)
		)
	)
)
